(kicad_pcb
	(version 20221018)
	(generator pcbnew)
	(general
    (thickness 1.586)
  )
	(paper "A4")
	(title_block
    (date "2024-03-26")
    (rev "1.1.3")
		(comment 9 "footprints 47-51 of 146")
	)
	(layers
    (0 "F.Cu" signal)
    (1 "In1.Cu" power)
    (2 "In2.Cu" power)
    (31 "B.Cu" signal)
    (32 "B.Adhes" user "B.Adhesive")
    (33 "F.Adhes" user "F.Adhesive")
    (34 "B.Paste" user)
    (35 "F.Paste" user)
    (36 "B.SilkS" user "B.Silkscreen")
    (37 "F.SilkS" user "F.Silkscreen")
    (38 "B.Mask" user)
    (39 "F.Mask" user)
    (40 "Dwgs.User" user "User.Drawings")
    (41 "Cmts.User" user "User.Comments")
    (42 "Eco1.User" user "User.Eco1")
    (43 "Eco2.User" user "User.Eco2")
    (44 "Edge.Cuts" user)
    (45 "Margin" user)
    (46 "B.CrtYd" user "B.Courtyard")
    (47 "F.CrtYd" user "F.Courtyard")
    (48 "B.Fab" user)
    (49 "F.Fab" user)
  )
	(footprint "scalenode-cm4-baseboard-footprints:R_0402_1005Metric" (layer "F.Cu")
    (at 93.8 87.1 90)
    (descr "Resistor SMD 0402")
    (tags "resistor SMD 0402")
    (property "Author" "Antmicro")
    (property "DNP" "DNP")
    (property "License" "Apache-2.0")
    (property "MPN" "CR0402-FX-1002GLF")
    (property "Manufacturer" "Bourns")
    (property "Sheetfile" "poe.kicad_sch")
    (property "Sheetname" "PoE")
    (property "Tolerance" "1%")
    (property "Val" "10k")
    (property "dnp" "")
    (property "exclude_from_bom" "")
    (property "ki_description" "10k resistor in 0402 package with 1% tolerance")
    (attr exclude_from_pos_files exclude_from_bom)
    (fp_text reference "R40" (at 0.975 0.4 90) (layer "F.SilkS")
        (effects (font (size 0.7 0.7) (thickness 0.15)) (justify left bottom))
    )
    (fp_text value "R_10k_0402" (at 0 1.4 90) (layer "F.Fab")
        (effects (font (size 0.7 0.7) (thickness 0.15)) (justify left bottom))
    )
    (fp_text user "Author: Antmicro" (at -0.95 4.169 90) (layer "F.Fab") hide
        (effects (font (size 0.7 0.7) (thickness 0.15)) (justify left bottom))
    )
    (fp_text user "${REFERENCE}" (at -0.95 3.168 90) (layer "F.Fab") hide
        (effects (font (size 0.7 0.7) (thickness 0.15)) (justify left bottom))
    )
    (fp_text user "License: Apache-2.0" (at -0.95 5.169 90) (layer "F.Fab") hide
        (effects (font (size 0.7 0.7) (thickness 0.15)) (justify left bottom))
    )
    (fp_rect (start -0.95 -0.48) (end 0.95 0.48)
      (stroke (width 0.05) (type solid)) (fill none) (layer "F.CrtYd"))
    (fp_rect (start -0.5 -0.25) (end 0.5 0.25)
      (stroke (width 0.15) (type solid)) (fill none) (layer "F.Fab"))
    (pad "1" smd roundrect (at -0.485 0 90) (size 0.59 0.64) (layers "F.Cu" "F.Paste" "F.Mask") (roundrect_rratio 0.25)
      (net 262 "Net-(U3-TPL)") (pintype "passive"))
    (pad "2" smd roundrect (at 0.485 0 90) (size 0.59 0.64) (layers "F.Cu" "F.Paste" "F.Mask") (roundrect_rratio 0.25)
      (net 6 "/PoE/VDD_POE_IN") (pintype "passive"))
  )
	(footprint "scalenode-cm4-baseboard-footprints:VQFN-20_5x5x1mm_P0.65mm" (layer "F.Cu")
    (at 92.4 91.4)
    (property "Author" "Antmicro")
    (property "DNP" "DNP")
    (property "License" "Apache-2.0")
    (property "MPN" "TPS2373-3RGWR")
    (property "Manufacturer" "Texas Instruments")
    (property "Sheetfile" "poe.kicad_sch")
    (property "Sheetname" "PoE")
    (property "dnp" "")
    (property "exclude_from_bom" "")
    (property "ki_description" "High-Power PoE PD Interface with Advanced Startup")
    (attr exclude_from_pos_files exclude_from_bom)
    (fp_text reference "U3" (at -4.65 -1.15) (layer "F.SilkS")
        (effects (font (size 0.7 0.7) (thickness 0.15)) (justify left bottom))
    )
    (fp_text value "TPS2373-3RGW" (at 0 3.883) (layer "F.Fab")
        (effects (font (size 0.7 0.7) (thickness 0.15)) (justify left bottom))
    )
    (fp_text user "Author: Antmicro" (at -2.5 6.884) (layer "F.Fab") hide
        (effects (font (size 0.7 0.7) (thickness 0.15)) (justify left bottom))
    )
    (fp_text user "${REFERENCE}" (at -2.5 5.884) (layer "F.Fab") hide
        (effects (font (size 0.7 0.7) (thickness 0.15)) (justify left bottom))
    )
    (fp_text user "License: Apache-2.0" (at -2.5 7.884) (layer "F.Fab") hide
        (effects (font (size 0.7 0.7) (thickness 0.15)) (justify left bottom))
    )
    (fp_poly
      (pts
        (xy -1.081 -1.081)
        (xy -0.11 -1.081)
        (xy -0.11 -0.09)
        (xy -1.081 -0.09)
      )

      (stroke (width 0.01) (type solid)) (fill solid) (layer "F.Paste"))
    (fp_poly
      (pts
        (xy -1.081 0.088)
        (xy -0.11 0.088)
        (xy -0.11 1.08)
        (xy -1.081 1.08)
      )

      (stroke (width 0.01) (type solid)) (fill solid) (layer "F.Paste"))
    (fp_poly
      (pts
        (xy 0.108 -1.081)
        (xy 1.08 -1.081)
        (xy 1.08 -0.09)
        (xy 0.108 -0.09)
      )

      (stroke (width 0.01) (type solid)) (fill solid) (layer "F.Paste"))
    (fp_poly
      (pts
        (xy 0.108 0.088)
        (xy 1.08 0.088)
        (xy 1.08 1.08)
        (xy 0.108 1.08)
      )

      (stroke (width 0.01) (type solid)) (fill solid) (layer "F.Paste"))
    (fp_line (start -2.5 2.499) (end -2.5 1.789)
      (stroke (width 0.15) (type solid)) (layer "F.SilkS"))
    (fp_line (start -2.5 2.499) (end -1.79 2.499)
      (stroke (width 0.15) (type solid)) (layer "F.SilkS"))
    (fp_line (start -1.625 -2.5) (end -2.5 -2.5)
      (stroke (width 0.15) (type solid)) (layer "F.SilkS"))
    (fp_line (start 2.499 -2.5) (end 1.789 -2.5)
      (stroke (width 0.15) (type solid)) (layer "F.SilkS"))
    (fp_line (start 2.499 -2.5) (end 2.499 -1.79)
      (stroke (width 0.15) (type solid)) (layer "F.SilkS"))
    (fp_line (start 2.499 2.499) (end 1.789 2.499)
      (stroke (width 0.15) (type solid)) (layer "F.SilkS"))
    (fp_line (start 2.499 2.499) (end 2.499 1.789)
      (stroke (width 0.15) (type solid)) (layer "F.SilkS"))
    (fp_circle (center -2.775 -1.875) (end -2.725 -1.825)
      (stroke (width 0.15) (type solid)) (fill solid) (layer "F.SilkS"))
    (fp_rect (start -2.95 -2.95) (end 2.95 2.95)
      (stroke (width 0.05) (type solid)) (fill none) (layer "F.CrtYd"))
    (fp_line (start -2.5 -1.65) (end -1.65 -2.5)
      (stroke (width 0.15) (type solid)) (layer "F.Fab"))
    (fp_line (start -2.5 2.499) (end -2.5 -1.65)
      (stroke (width 0.15) (type solid)) (layer "F.Fab"))
    (fp_line (start 2.499 -2.5) (end -1.65 -2.5)
      (stroke (width 0.15) (type solid)) (layer "F.Fab"))
    (fp_line (start 2.499 2.499) (end -2.5 2.499)
      (stroke (width 0.15) (type solid)) (layer "F.Fab"))
    (fp_line (start 2.499 2.499) (end 2.499 -2.5)
      (stroke (width 0.15) (type solid)) (layer "F.Fab"))
    (pad "1" smd roundrect (at -2.327 -1.301) (size 0.75 0.31) (layers "F.Cu" "F.Paste" "F.Mask") (roundrect_rratio 0.25)
      (net 6 "/PoE/VDD_POE_IN") (pinfunction "VDD") (pintype "power_in"))
    (pad "2" smd roundrect (at -2.327 -0.652) (size 0.75 0.31) (layers "F.Cu" "F.Paste" "F.Mask") (roundrect_rratio 0.25)
      (net 258 "Net-(U3-DEN)") (pinfunction "DEN") (pintype "input"))
    (pad "3" smd roundrect (at -2.327 0) (size 0.75 0.31) (layers "F.Cu" "F.Paste" "F.Mask") (roundrect_rratio 0.25)
      (net 254 "Net-(U3-CLSA)") (pinfunction "CLSA") (pintype "input"))
    (pad "4" smd roundrect (at -2.327 0.65) (size 0.75 0.31) (layers "F.Cu" "F.Paste" "F.Mask") (roundrect_rratio 0.25)
      (net 5 "VSS") (pinfunction "VSS") (pintype "power_in"))
    (pad "5" smd roundrect (at -2.327 1.3) (size 0.75 0.31) (layers "F.Cu" "F.Paste" "F.Mask") (roundrect_rratio 0.25)
      (net 5 "VSS") (pinfunction "VSS") (pintype "passive"))
    (pad "6" smd roundrect (at -1.301 2.325) (size 0.31 0.75) (layers "F.Cu" "F.Paste" "F.Mask") (roundrect_rratio 0.25)
      (net 257 "Net-(U3-CLSB)") (pinfunction "CLSB") (pintype "input"))
    (pad "7" smd roundrect (at -0.652 2.325) (size 0.31 0.75) (layers "F.Cu" "F.Paste" "F.Mask") (roundrect_rratio 0.25)
      (net 260 "Net-(U3-REF)") (pinfunction "REF") (pintype "input"))
    (pad "8" smd roundrect (at 0 2.325) (size 0.31 0.75) (layers "F.Cu" "F.Paste" "F.Mask") (roundrect_rratio 0.25)
      (net 259 "Net-(U3-AMPS_CTL)") (pinfunction "AMPS_CTL") (pintype "input"))
    (pad "9" smd roundrect (at 0.65 2.325) (size 0.31 0.75) (layers "F.Cu" "F.Paste" "F.Mask") (roundrect_rratio 0.25)
      (net 5 "VSS") (pinfunction "MPS_DUTY") (pintype "input"))
    (pad "10" smd roundrect (at 1.3 2.325) (size 0.31 0.75) (layers "F.Cu" "F.Paste" "F.Mask") (roundrect_rratio 0.25)
      (net 4 "GNDD") (pinfunction "APD") (pintype "input"))
    (pad "11" smd roundrect (at 2.325 1.3) (size 0.75 0.31) (layers "F.Cu" "F.Paste" "F.Mask") (roundrect_rratio 0.25)
      (net 4 "GNDD") (pinfunction "RTN") (pintype "power_out"))
    (pad "12" smd roundrect (at 2.325 0.65) (size 0.75 0.31) (layers "F.Cu" "F.Paste" "F.Mask") (roundrect_rratio 0.25)
      (net 4 "GNDD") (pinfunction "RTN") (pintype "passive"))
    (pad "13" smd roundrect (at 2.325 0) (size 0.75 0.31) (layers "F.Cu" "F.Paste" "F.Mask") (roundrect_rratio 0.25)
      (net 34 "/PoE/POE_ACTIVE") (pinfunction "PG") (pintype "output"))
    (pad "14" smd roundrect (at 2.325 -0.652) (size 0.75 0.31) (layers "F.Cu" "F.Paste" "F.Mask") (roundrect_rratio 0.25)
      (net 271 "Net-(U3-VC_OUT)") (pinfunction "VC_OUT") (pintype "output"))
    (pad "15" smd roundrect (at 2.325 -1.301) (size 0.75 0.31) (layers "F.Cu" "F.Paste" "F.Mask") (roundrect_rratio 0.25)
      (net 269 "Net-(U3-VC_IN)") (pinfunction "VC_IN") (pintype "input"))
    (pad "16" smd roundrect (at 1.3 -2.327) (size 0.31 0.75) (layers "F.Cu" "F.Paste" "F.Mask") (roundrect_rratio 0.25)
      (net 272 "Net-(U3-UVLO_SEL)") (pinfunction "UVLO_SEL") (pintype "output"))
    (pad "17" smd roundrect (at 0.65 -2.327) (size 0.31 0.75) (layers "F.Cu" "F.Paste" "F.Mask") (roundrect_rratio 0.25)
      (net 262 "Net-(U3-TPL)") (pinfunction "TPL") (pintype "output"))
    (pad "18" smd roundrect (at 0 -2.327) (size 0.31 0.75) (layers "F.Cu" "F.Paste" "F.Mask") (roundrect_rratio 0.25)
      (net 261 "Net-(U3-TPH)") (pinfunction "TPH") (pintype "output"))
    (pad "19" smd roundrect (at -0.652 -2.327) (size 0.31 0.75) (layers "F.Cu" "F.Paste" "F.Mask") (roundrect_rratio 0.25)
      (net 263 "Net-(U3-~{BT})") (pinfunction "~{BT}") (pintype "output"))
    (pad "20" smd roundrect (at -1.301 -2.327) (size 0.31 0.75) (layers "F.Cu" "F.Paste" "F.Mask") (roundrect_rratio 0.25))
    (pad "21" smd rect (at 0 0) (size 2.2 2.2) (layers "F.Cu" "F.Mask")
      (net 5 "VSS") (pinfunction "VSS") (pintype "passive"))
  )
	(footprint "scalenode-cm4-baseboard-footprints:LED_0603_1608Metric_G" (layer "F.Cu")
    (at 76.1 78.681 -90)
    (descr "LED SMD 0603 Red")
    (tags "LED SMD 0603 Red")
    (property "Author" "Antmicro")
    (property "License" "Apache-2.0")
    (property "MPN" "598-8D80-107F")
    (property "Manufacturer" "Dialight")
    (property "Sheetfile" "nvme-ssd.kicad_sch")
    (property "Sheetname" "NVMe SSD")
    (attr smd)
    (fp_text reference "D1" (at -0.735969 -1.474009 90) (layer "F.SilkS")
        (effects (font (size 0.7 0.7) (thickness 0.15)) (justify right bottom))
    )
    (fp_text value "LED_G_0603_598-8D80-107F" (at 0 1.6 90) (layer "F.Fab")
        (effects (font (size 0.7 0.7) (thickness 0.15)) (justify right bottom))
    )
    (fp_text user "Author: Antmicro" (at -1.31 4.769 90) (layer "F.Fab") hide
        (effects (font (size 0.7 0.7) (thickness 0.15)) (justify right bottom))
    )
    (fp_text user "${REFERENCE}" (at -1.31 3.769 90) (layer "F.Fab") hide
        (effects (font (size 0.7 0.7) (thickness 0.15)) (justify right bottom))
    )
    (fp_text user "License: Apache-2.0" (at -1.31 5.769 90) (layer "F.Fab") hide
        (effects (font (size 0.7 0.7) (thickness 0.15)) (justify right bottom))
    )
    (fp_line (start -0.27 -0.35) (end 0.27 -0.35)
      (stroke (width 0.15) (type solid)) (layer "F.SilkS"))
    (fp_line (start -0.27 0.351) (end 0.27 0.351)
      (stroke (width 0.15) (type solid)) (layer "F.SilkS"))
    (fp_line (start -0.106328 -0.200008) (end -0.106328 0.199992)
      (stroke (width 0.1) (type solid)) (layer "F.SilkS"))
    (fp_line (start -0.106328 -0.200008) (end 0.093672 -0.000008)
      (stroke (width 0.1) (type solid)) (layer "F.SilkS"))
    (fp_line (start -0.106328 -0.000008) (end -0.29 0)
      (stroke (width 0.1) (type solid)) (layer "F.SilkS"))
    (fp_line (start 0.093672 -0.200008) (end 0.093672 0.199992)
      (stroke (width 0.1) (type solid)) (layer "F.SilkS"))
    (fp_line (start 0.093672 -0.000008) (end -0.106328 0.199992)
      (stroke (width 0.1) (type solid)) (layer "F.SilkS"))
    (fp_line (start 0.093672 -0.000008) (end 0.293672 -0.000008)
      (stroke (width 0.1) (type solid)) (layer "F.SilkS"))
    (fp_line (start 1.25 0.32) (end 1.25 -0.32)
      (stroke (width 0.15) (type solid)) (layer "F.SilkS"))
    (fp_rect (start 1.26 0.65) (end -1.26 -0.65)
      (stroke (width 0.05) (type solid)) (fill none) (layer "F.CrtYd"))
    (fp_line (start -0.599 0) (end -0.201 0)
      (stroke (width 0.15) (type solid)) (layer "F.Fab"))
    (fp_line (start -0.201 -0.2) (end -0.201 0)
      (stroke (width 0.15) (type solid)) (layer "F.Fab"))
    (fp_line (start -0.201 0) (end -0.201 0.202)
      (stroke (width 0.15) (type solid)) (layer "F.Fab"))
    (fp_line (start -0.201 0.202) (end 0.101 0)
      (stroke (width 0.15) (type solid)) (layer "F.Fab"))
    (fp_line (start 0.101 0) (end -0.201 -0.2)
      (stroke (width 0.15) (type solid)) (layer "F.Fab"))
    (fp_line (start 0.199 -0.2) (end 0.199 -0.1)
      (stroke (width 0.15) (type solid)) (layer "F.Fab"))
    (fp_line (start 0.199 0) (end 0.597 0)
      (stroke (width 0.15) (type solid)) (layer "F.Fab"))
    (fp_line (start 0.199 0.202) (end 0.199 -0.1)
      (stroke (width 0.15) (type solid)) (layer "F.Fab"))
    (fp_rect (start -0.848 -0.4) (end 0.85 0.402)
      (stroke (width 0.15) (type solid)) (fill none) (layer "F.Fab"))
    (pad "1" smd rect (at -0.75 0 90) (size 0.8 0.8) (layers "F.Cu" "F.Paste" "F.Mask")
      (net 188 "Net-(D1-Pad1)") (pinfunction "1") (pintype "passive"))
    (pad "2" smd rect (at 0.75 0 90) (size 0.8 0.8) (layers "F.Cu" "F.Paste" "F.Mask")
      (net 26 "Net-(J3-LED)") (pinfunction "2") (pintype "passive"))
  )
	(footprint "scalenode-cm4-baseboard-footprints:URB4805YMD-30WR3" (layer "F.Cu")
    (at 117.09 73.05)
    (property "Author" "Antmicro")
    (property "DNP" "DNP")
    (property "License" "Apache-2.0")
    (property "MPN" "URB4805YMD-30WR3")
    (property "Manufacturer" "Mornsun")
    (property "Sheetfile" "poe.kicad_sch")
    (property "Sheetname" "PoE")
    (property "dnp" "")
    (property "exclude_from_bom" "")
    (property "ki_description" "DC-DC CONVERTER, 48VDC input, 5VDC nom isolated output w/ trim option, 30W, 270kHz PWM mode")
    (property "ki_keywords" "dc converter step down 5v 48v isolated 30W poe")
    (attr exclude_from_pos_files exclude_from_bom)
    (fp_text reference "U4" (at -2.74 -2.83) (layer "F.SilkS")
        (effects (font (size 0.7 0.7) (thickness 0.15)) (justify left bottom))
    )
    (fp_text value "URB4805YMD-30WR3" (at 10.885 20.75) (layer "F.Fab")
        (effects (font (size 0.7 0.7) (thickness 0.15)) (justify left bottom))
    )
    (fp_text user "Author: Antmicro" (at -3.44 28.193) (layer "F.Fab") hide
        (effects (font (size 0.7 0.7) (thickness 0.15)) (justify left bottom))
    )
    (fp_text user "${REFERENCE}" (at -3.44 26.995 unlocked) (layer "F.Fab") hide
        (effects (font (size 0.7 0.7) (thickness 0.15)) (justify left bottom))
    )
    (fp_text user "Apache-2.0 License" (at 11.2 26) (layer "F.Fab") hide
        (effects (font (size 1 1) (thickness 0.15)))
    )
    (fp_text user "License: Apache-2.0" (at -3.44 25.795) (layer "F.Fab") hide
        (effects (font (size 0.7 0.7) (thickness 0.15)) (justify left bottom))
    )
    (fp_text user "Copyright (c) 2023 Antmicro" (at 11.07 25.27) (layer "F.Fab") hide
        (effects (font (size 1 1) (thickness 0.15)))
    )
    (fp_line (start -2.54 -2.54) (end 22.859 -2.54)
      (stroke (width 0.15) (type solid)) (layer "F.SilkS"))
    (fp_line (start -2.54 22.859) (end -2.54 -2.54)
      (stroke (width 0.15) (type solid)) (layer "F.SilkS"))
    (fp_line (start 22.859 -2.54) (end 22.859 22.859)
      (stroke (width 0.15) (type solid)) (layer "F.SilkS"))
    (fp_line (start 22.859 22.859) (end -2.54 22.859)
      (stroke (width 0.15) (type solid)) (layer "F.SilkS"))
    (fp_circle (center -3.048 0) (end -2.95 0)
      (stroke (width 0.15) (type solid)) (fill none) (layer "F.SilkS"))
    (fp_line (start -2.79 -2.79) (end 23.1 -2.79)
      (stroke (width 0.05) (type solid)) (layer "F.CrtYd"))
    (fp_line (start -2.79 23.1) (end -2.79 -2.79)
      (stroke (width 0.05) (type solid)) (layer "F.CrtYd"))
    (fp_line (start 23.1 -2.79) (end 23.1 23.1)
      (stroke (width 0.05) (type solid)) (layer "F.CrtYd"))
    (fp_line (start 23.1 23.1) (end -2.79 23.1)
      (stroke (width 0.05) (type solid)) (layer "F.CrtYd"))
    (fp_line (start -2.54 -2.54) (end -2.54 22.859)
      (stroke (width 0.15) (type solid)) (layer "F.Fab"))
    (fp_line (start -2.54 -2.54) (end 22.859 -2.54)
      (stroke (width 0.15) (type solid)) (layer "F.Fab"))
    (fp_line (start -2.54 22.859) (end 22.859 22.859)
      (stroke (width 0.15) (type solid)) (layer "F.Fab"))
    (fp_line (start 22.859 22.859) (end 22.859 -2.54)
      (stroke (width 0.15) (type solid)) (layer "F.Fab"))
    (fp_circle (center -3.048 0) (end -2.95 0)
      (stroke (width 0.15) (type solid)) (fill none) (layer "F.Fab"))
    (pad "1" thru_hole rect (at 0 0) (size 2.25 2.25) (drill 1.5) (layers "*.Cu" "*.Mask")
      (net 34 "/PoE/POE_ACTIVE") (pinfunction "CTRL") (pintype "input"))
    (pad "2" thru_hole circle (at 0 7.618) (size 2.25 2.25) (drill 1.5) (layers "*.Cu" "*.Mask")
      (net 4 "GNDD") (pinfunction "GND") (pintype "power_in"))
    (pad "3" thru_hole circle (at 0 12.698) (size 2.25 2.25) (drill 1.5) (layers "*.Cu" "*.Mask")
      (net 6 "/PoE/VDD_POE_IN") (pinfunction "V_{IN}") (pintype "power_in"))
    (pad "4" thru_hole circle (at 20.318 20.318) (size 2.25 2.25) (drill 1.5) (layers "*.Cu" "*.Mask")
      (net 13 "/PoE/VO5V") (pinfunction "V_{O}") (pintype "power_out"))
    (pad "5" thru_hole circle (at 20.318 10.159) (size 2.25 2.25) (drill 1.5) (layers "*.Cu" "*.Mask")
      (net 273 "unconnected-(U4-TRIM-Pad5)") (pinfunction "TRIM") (pintype "passive+no_connect"))
    (pad "6" thru_hole circle (at 20.318 0) (size 2.25 2.25) (drill 1.5) (layers "*.Cu" "*.Mask")
      (net 11 "GND") (pinfunction "0V") (pintype "power_out"))
  )
	(footprint "scalenode-cm4-baseboard-footprints:TP_SMD_1mm" (layer "F.Cu")
    (at 133.2 68.8842)
    (property "Author" "Antmicro")
    (property "License" "Apache-2.0")
    (property "MPN" "")
    (property "Manufacturer" "")
    (property "Sheetfile" "poe.kicad_sch")
    (property "Sheetname" "PoE")
    (property "ki_description" "Test Point 1mm")
    (attr exclude_from_pos_files)
    (fp_text reference "TP5" (at 0 -0.731898) (layer "F.SilkS") hide
        (effects (font (size 0.7 0.7) (thickness 0.15)) (justify left bottom))
    )
    (fp_text value "TP_1mm_SMD" (at 0 1.4) (layer "F.Fab")
        (effects (font (size 0.7 0.7) (thickness 0.15)) (justify left bottom))
    )
    (fp_text user "License: Apache-2.0" (at -0.5 5.2) (layer "F.Fab") hide
        (effects (font (size 0.7 0.7) (thickness 0.15)) (justify left bottom))
    )
    (fp_text user "Author: Antmicro" (at -0.5 4) (layer "F.Fab") hide
        (effects (font (size 0.7 0.7) (thickness 0.15)) (justify left bottom))
    )
    (fp_text user "${REFERENCE}" (at -0.5 2.8) (layer "F.Fab") hide
        (effects (font (size 0.7 0.7) (thickness 0.15)) (justify left bottom))
    )
    (pad "1" smd circle (at 0 0) (size 1 1) (layers "F.Cu" "F.Mask")
      (net 12 "VCC5V0") (pinfunction "1") (pintype "passive"))
  )
)
